# T6G (Grand Teton) — schematic netlist excerpt (pin names and nets, part order shuffled) for the footprints in the layout excerpt that follows; sources: Cadence DE-HDL packaged netlist, KiCad conversion of 04192023_DAF0TMB3IC0_F0TG_MB_C_brd_V02_OCP.brd

R1235  Q_RES  5.11K 1% CHIP  pkg 0402LF  page 258 : A = PVDD_33_S5 ; B = PVDD_33_S5_ADC

Q86  MOSFET_NCH_DUAL  PJT138K IC  pkg SOT363XD  page 256
  S1  = GND
  G1  = FM_LED_PWRGD_PVDD11_S3_P1
  D2  = LED_PWRGD_PVDD18_S5_P1_D
  S2  = GND
  G2  = FM_LED_PWRGD_PVDD18_S5_P1
  D1  = LED_PWRGD_PVDD11_S3_P1_D

(kicad_pcb
	(version 20260206)
	(generator "pcbnew")
	(generator_version "10.0")
	(general
		(thickness 1.6)
		(legacy_teardrops no)
	)
	(paper "A4")
	(title_block
		(title "04192023_DAF0TMB3IC0_F0TG_MB_C_brd_V02_OCP.brd")
		(comment 1 "Grand Teton / footprints 5444-5445 of 8354")
	)
	(layers
		(0 "F.Cu" signal "TOP")
		(4 "In1.Cu" signal "GND")
		(6 "In2.Cu" signal "IN1")
		(8 "In3.Cu" signal "GND1")
		(10 "In4.Cu" signal "IN2")
		(12 "In5.Cu" signal "GND2")
		(14 "In6.Cu" signal "IN3")
		(16 "In7.Cu" signal "GND3")
		(18 "In8.Cu" signal "VCC")
		(20 "In9.Cu" signal "VCC1")
		(22 "In10.Cu" signal "GND4")
		(24 "In11.Cu" signal "IN4")
		(26 "In12.Cu" signal "GND5")
		(28 "In13.Cu" signal "IN5")
		(30 "In14.Cu" signal "GND6")
		(32 "In15.Cu" signal "IN6")
		(34 "In16.Cu" signal "GND7")
		(2 "B.Cu" signal "BOTTOM")
		(9 "F.Adhes" user "F.Adhesive")
		(11 "B.Adhes" user "B.Adhesive")
		(13 "F.Paste" user "Package Geometry/Pastemask Top")
		(15 "B.Paste" user "Package Geometry/Pastemask Bottom")
		(5 "F.SilkS" user "Ref Des/Silkscreen Top")
		(7 "B.SilkS" user "Ref Des/Silkscreen Bottom")
		(1 "F.Mask" user "Board Geometry/Soldermask Top")
		(3 "B.Mask" user "Board Geometry/Soldermask Bottom")
		(17 "Dwgs.User" user "User.Drawings")
		(19 "Cmts.User" user "User.Comments")
		(21 "Eco1.User" user "User.Eco1")
		(23 "Eco2.User" user "User.Eco2")
		(25 "Edge.Cuts" user "Board Geometry/Outline")
		(27 "Margin" user)
		(31 "F.CrtYd" user "Package Geometry/Place Bound Top")
		(29 "B.CrtYd" user "Package Geometry/Place Bound Bottom")
		(35 "F.Fab" user "Ref Des/Assembly Top")
		(33 "B.Fab" user "Ref Des/Assembly Bottom")
	)
	(footprint ""
		(layer "B.Cu")
		(at 346.688664 -73.534778)
		(property "Reference" "Q86"
			(at 1.4224 -1.768348 0)
			(unlocked yes)
			(layer "B.SilkS")
			(effects
				(font
					(size 0.7874 0.5842)
					(thickness 0.1524)
				)
				(justify left mirror)
			)
		)
		(property "Value" ""
			(at 0 0 0)
			(layer "B.Fab")
			(effects
				(font
					(size 1.27 1.27)
				)
				(justify mirror)
			)
		)
		(duplicate_pad_numbers_are_jumpers no)
		(fp_line
			(start -1.332738 -1.100074)
			(end -1.332738 1.100074)
			(stroke
				(width 0.1524)
				(type default)
			)
			(layer "B.SilkS")
		)
		(fp_line
			(start -1.332738 1.100074)
			(end 1.332738 1.100074)
			(stroke
				(width 0.1524)
				(type default)
			)
			(layer "B.SilkS")
		)
		(fp_line
			(start -0.4826 -1.100074)
			(end -1.332738 -1.100074)
			(stroke
				(width 0.1524)
				(type default)
			)
			(layer "B.SilkS")
		)
		(fp_line
			(start 0 -0.541274)
			(end -0.4826 -1.100074)
			(stroke
				(width 0.1524)
				(type default)
			)
			(layer "B.SilkS")
		)
		(fp_line
			(start 0.4826 -1.100074)
			(end 0 -0.541274)
			(stroke
				(width 0.1524)
				(type default)
			)
			(layer "B.SilkS")
		)
		(fp_line
			(start 1.332738 -1.100074)
			(end 0.4826 -1.100074)
			(stroke
				(width 0.1524)
				(type default)
			)
			(layer "B.SilkS")
		)
		(fp_line
			(start 1.332738 1.100074)
			(end 1.332738 -1.100074)
			(stroke
				(width 0.1524)
				(type default)
			)
			(layer "B.SilkS")
		)
		(fp_poly
			(pts
				(xy 1.422654 -0.649986) (xy 2.12471 -1.001014) (xy 2.12471 -0.298958)
			)
			(stroke
				(width 0)
				(type default)
			)
			(fill yes)
			(layer "B.SilkS")
		)
		(fp_line
			(start -0.674878 -1.100074)
			(end -0.674878 1.100074)
			(stroke
				(width 0.1)
				(type default)
			)
			(layer "B.Fab")
		)
		(fp_line
			(start -0.674878 1.100074)
			(end 0.674878 1.100074)
			(stroke
				(width 0.1)
				(type default)
			)
			(layer "B.Fab")
		)
		(fp_line
			(start 0.674878 -1.100074)
			(end -0.674878 -1.100074)
			(stroke
				(width 0.1)
				(type default)
			)
			(layer "B.Fab")
		)
		(fp_line
			(start 0.674878 1.100074)
			(end 0.674878 -1.100074)
			(stroke
				(width 0.1)
				(type default)
			)
			(layer "B.Fab")
		)
		(fp_poly
			(pts
				(xy 2.2352 -0.298958) (xy 2.2352 -1.001014) (xy 1.533144 -0.649986)
			)
			(stroke
				(width 0)
				(type default)
			)
			(fill yes)
			(layer "B.Fab")
		)
		(pad "1" smd rect
			(at 0.94996 -0.649986 90)
			(size 0.4318 0.508)
			(layers "B.Cu" "B.Mask" "B.Paste")
			(net "GND")
		)
		(pad "2" smd rect
			(at 0.94996 0 90)
			(size 0.4318 0.508)
			(layers "B.Cu" "B.Mask" "B.Paste")
			(net "FM_LED_PWRGD_PVDD11_S3_P1")
		)
		(pad "3" smd rect
			(at 0.94996 0.649986 90)
			(size 0.4318 0.508)
			(layers "B.Cu" "B.Mask" "B.Paste")
			(net "LED_PWRGD_PVDD18_S5_P1_D")
		)
		(pad "4" smd rect
			(at -0.94996 0.649986 90)
			(size 0.4318 0.508)
			(layers "B.Cu" "B.Mask" "B.Paste")
			(net "GND")
		)
		(pad "5" smd rect
			(at -0.94996 0 90)
			(size 0.4318 0.508)
			(layers "B.Cu" "B.Mask" "B.Paste")
			(net "FM_LED_PWRGD_PVDD18_S5_P1")
		)
		(pad "6" smd rect
			(at -0.94996 -0.649986 90)
			(size 0.4318 0.508)
			(layers "B.Cu" "B.Mask" "B.Paste")
			(net "LED_PWRGD_PVDD11_S3_P1_D")
		)
	)
	(footprint ""
		(layer "B.Cu")
		(at 237.910624 -326.683624)
		(property "Reference" "R1235"
			(at 0 0 0)
			(layer "B.SilkS")
			(hide yes)
			(effects
				(font
					(size 1.27 1.27)
				)
				(justify mirror)
			)
		)
		(property "Value" ""
			(at 0 0 0)
			(layer "B.Fab")
			(effects
				(font
					(size 1.27 1.27)
				)
				(justify mirror)
			)
		)
		(duplicate_pad_numbers_are_jumpers no)
		(fp_line
			(start -0.7874 -0.4064)
			(end -0.7874 0.4064)
			(stroke
				(width 0.1524)
				(type default)
			)
			(layer "B.SilkS")
		)
		(fp_line
			(start -0.7874 0.4064)
			(end 0.7874 0.4064)
			(stroke
				(width 0.1524)
				(type default)
			)
			(layer "B.SilkS")
		)
		(fp_line
			(start 0.7874 -0.4064)
			(end -0.7874 -0.4064)
			(stroke
				(width 0.1524)
				(type default)
			)
			(layer "B.SilkS")
		)
		(fp_line
			(start 0.7874 0.4064)
			(end 0.7874 -0.4064)
			(stroke
				(width 0.1524)
				(type default)
			)
			(layer "B.SilkS")
		)
		(fp_line
			(start -0.67945 -0.3048)
			(end -0.67945 0.3048)
			(stroke
				(width 0.1)
				(type default)
			)
			(layer "B.Fab")
		)
		(fp_line
			(start -0.67945 0.3048)
			(end -0.120396 0.3048)
			(stroke
				(width 0.1)
				(type default)
			)
			(layer "B.Fab")
		)
		(fp_line
			(start -0.12065 -0.3048)
			(end -0.67945 -0.3048)
			(stroke
				(width 0.1)
				(type default)
			)
			(layer "B.Fab")
		)
		(fp_line
			(start -0.12065 -0.2794)
			(end -0.12065 -0.3048)
			(stroke
				(width 0.1)
				(type default)
			)
			(layer "B.Fab")
		)
		(fp_line
			(start -0.120396 0.2794)
			(end 0.12065 0.2794)
			(stroke
				(width 0.1)
				(type default)
			)
			(layer "B.Fab")
		)
		(fp_line
			(start -0.120396 0.3048)
			(end -0.120396 0.2794)
			(stroke
				(width 0.1)
				(type default)
			)
			(layer "B.Fab")
		)
		(fp_line
			(start 0.12065 -0.305054)
			(end 0.12065 -0.2794)
			(stroke
				(width 0.1)
				(type default)
			)
			(layer "B.Fab")
		)
		(fp_line
			(start 0.12065 -0.2794)
			(end -0.12065 -0.2794)
			(stroke
				(width 0.1)
				(type default)
			)
			(layer "B.Fab")
		)
		(fp_line
			(start 0.12065 0.2794)
			(end 0.12065 0.3048)
			(stroke
				(width 0.1)
				(type default)
			)
			(layer "B.Fab")
		)
		(fp_line
			(start 0.12065 0.3048)
			(end 0.67945 0.3048)
			(stroke
				(width 0.1)
				(type default)
			)
			(layer "B.Fab")
		)
		(fp_line
			(start 0.67945 -0.305054)
			(end 0.12065 -0.305054)
			(stroke
				(width 0.1)
				(type default)
			)
			(layer "B.Fab")
		)
		(fp_line
			(start 0.67945 0.3048)
			(end 0.67945 -0.305054)
			(stroke
				(width 0.1)
				(type default)
			)
			(layer "B.Fab")
		)
		(pad "1" smd circle
			(at 0.40005 0 180)
			(size 0 0)
			(layers "B.Cu" "B.Mask" "B.Paste")
			(net "PVDD_33_S5")
		)
		(pad "2" smd circle
			(at -0.40005 0 180)
			(size 0 0)
			(layers "B.Cu" "B.Mask" "B.Paste")
			(net "PVDD_33_S5_ADC")
		)
	)
)
